# S9S_MB_2U (Grand Teton) — schematic netlist excerpt (pin names and nets, part order shuffled) for the footprints in the layout excerpt that follows; sources: Cadence DE-HDL packaged netlist, KiCad conversion of 03242023_DA0F0TMBIJ0_F0T_Motherboard_J_brd_V01_OCP.brd

C114  Q_CAP  0.047UF 25V 10% X7R  pkg C0402  page 210 : A = P3V3_AUX_CLK_GEN_VDDA25M_CK440 ; B = GND
R243  Q_RES  100 1% CHIP  pkg 0402LF  page 121 : A = PVNN_TERM_CPU0 ; B = H_CPU0_PROCHOT_LVC1_N

(kicad_pcb
	(version 20260206)
	(generator "pcbnew")
	(generator_version "10.0")
	(general
		(thickness 1.6)
		(legacy_teardrops no)
	)
	(paper "A4")
	(title_block
		(title "03242023_DA0F0TMBIJ0_F0T_Motherboard_J_brd_V01_OCP.brd")
		(comment 1 "Grand Teton / footprints 5242-5243 of 6105")
	)
	(layers
		(0 "F.Cu" signal "TOP")
		(4 "In1.Cu" signal "GND")
		(6 "In2.Cu" signal "IN1")
		(8 "In3.Cu" signal "GND1")
		(10 "In4.Cu" signal "IN2")
		(12 "In5.Cu" signal "GND2")
		(14 "In6.Cu" signal "IN3")
		(16 "In7.Cu" signal "GND3")
		(18 "In8.Cu" signal "VCC")
		(20 "In9.Cu" signal "VCC1")
		(22 "In10.Cu" signal "GND4")
		(24 "In11.Cu" signal "IN4")
		(26 "In12.Cu" signal "GND5")
		(28 "In13.Cu" signal "IN5")
		(30 "In14.Cu" signal "GND6")
		(32 "In15.Cu" signal "IN6")
		(34 "In16.Cu" signal "GND7")
		(2 "B.Cu" signal "BOTTOM")
		(9 "F.Adhes" user "F.Adhesive")
		(11 "B.Adhes" user "B.Adhesive")
		(13 "F.Paste" user "Package Geometry/Pastemask Top")
		(15 "B.Paste" user "Package Geometry/Pastemask Bottom")
		(5 "F.SilkS" user "Ref Des/Silkscreen Top")
		(7 "B.SilkS" user "Ref Des/Silkscreen Bottom")
		(1 "F.Mask" user "Board Geometry/Soldermask Top")
		(3 "B.Mask" user "Board Geometry/Soldermask Bottom")
		(17 "Dwgs.User" user "User.Drawings")
		(19 "Cmts.User" user "User.Comments")
		(21 "Eco1.User" user "User.Eco1")
		(23 "Eco2.User" user "User.Eco2")
		(25 "Edge.Cuts" user "Board Geometry/Outline")
		(27 "Margin" user)
		(31 "F.CrtYd" user "Package Geometry/Place Bound Top")
		(29 "B.CrtYd" user "Package Geometry/Place Bound Bottom")
		(35 "F.Fab" user "Ref Des/Assembly Top")
		(33 "B.Fab" user "Ref Des/Assembly Bottom")
	)
	(footprint ""
		(layer "B.Cu")
		(at 318.223138 -189.73673 90)
		(property "Reference" "R243"
			(at 0 0 90)
			(layer "B.SilkS")
			(hide yes)
			(effects
				(font
					(size 1.27 1.27)
				)
				(justify mirror)
			)
		)
		(property "Value" ""
			(at 0 0 90)
			(layer "B.Fab")
			(effects
				(font
					(size 1.27 1.27)
				)
				(justify mirror)
			)
		)
		(duplicate_pad_numbers_are_jumpers no)
		(fp_line
			(start 0.7874 -0.4064)
			(end -0.7874 -0.4064)
			(stroke
				(width 0.1524)
				(type default)
			)
			(layer "B.SilkS")
		)
		(fp_line
			(start -0.7874 -0.4064)
			(end -0.7874 0.4064)
			(stroke
				(width 0.1524)
				(type default)
			)
			(layer "B.SilkS")
		)
		(fp_line
			(start 0.7874 0.4064)
			(end 0.7874 -0.4064)
			(stroke
				(width 0.1524)
				(type default)
			)
			(layer "B.SilkS")
		)
		(fp_line
			(start -0.7874 0.4064)
			(end 0.7874 0.4064)
			(stroke
				(width 0.1524)
				(type default)
			)
			(layer "B.SilkS")
		)
		(fp_line
			(start 0.67945 -0.305054)
			(end 0.12065 -0.305054)
			(stroke
				(width 0.1)
				(type default)
			)
			(layer "B.Fab")
		)
		(fp_line
			(start 0.12065 -0.305054)
			(end 0.12065 -0.2794)
			(stroke
				(width 0.1)
				(type default)
			)
			(layer "B.Fab")
		)
		(fp_line
			(start -0.12065 -0.3048)
			(end -0.67945 -0.3048)
			(stroke
				(width 0.1)
				(type default)
			)
			(layer "B.Fab")
		)
		(fp_line
			(start -0.67945 -0.3048)
			(end -0.67945 0.3048)
			(stroke
				(width 0.1)
				(type default)
			)
			(layer "B.Fab")
		)
		(fp_line
			(start 0.12065 -0.2794)
			(end -0.12065 -0.2794)
			(stroke
				(width 0.1)
				(type default)
			)
			(layer "B.Fab")
		)
		(fp_line
			(start -0.12065 -0.2794)
			(end -0.12065 -0.3048)
			(stroke
				(width 0.1)
				(type default)
			)
			(layer "B.Fab")
		)
		(fp_line
			(start 0.12065 0.2794)
			(end 0.12065 0.3048)
			(stroke
				(width 0.1)
				(type default)
			)
			(layer "B.Fab")
		)
		(fp_line
			(start -0.120396 0.2794)
			(end 0.12065 0.2794)
			(stroke
				(width 0.1)
				(type default)
			)
			(layer "B.Fab")
		)
		(fp_line
			(start 0.67945 0.3048)
			(end 0.67945 -0.305054)
			(stroke
				(width 0.1)
				(type default)
			)
			(layer "B.Fab")
		)
		(fp_line
			(start 0.12065 0.3048)
			(end 0.67945 0.3048)
			(stroke
				(width 0.1)
				(type default)
			)
			(layer "B.Fab")
		)
		(fp_line
			(start -0.120396 0.3048)
			(end -0.120396 0.2794)
			(stroke
				(width 0.1)
				(type default)
			)
			(layer "B.Fab")
		)
		(fp_line
			(start -0.67945 0.3048)
			(end -0.120396 0.3048)
			(stroke
				(width 0.1)
				(type default)
			)
			(layer "B.Fab")
		)
		(pad "1" smd circle
			(at 0.40005 0 270)
			(size 0 0)
			(layers "B.Cu" "B.Mask" "B.Paste")
			(net "PVNN_TERM_CPU0")
		)
		(pad "2" smd circle
			(at -0.40005 0 270)
			(size 0 0)
			(layers "B.Cu" "B.Mask" "B.Paste")
			(net "H_CPU0_PROCHOT_LVC1_N")
		)
	)
	(footprint ""
		(layer "B.Cu")
		(at 252.242574 -101.754178 180)
		(property "Reference" "C114"
			(at 0 0 0)
			(layer "B.SilkS")
			(hide yes)
			(effects
				(font
					(size 1.27 1.27)
				)
				(justify mirror)
			)
		)
		(property "Value" ""
			(at 0 0 0)
			(layer "B.Fab")
			(effects
				(font
					(size 1.27 1.27)
				)
				(justify mirror)
			)
		)
		(duplicate_pad_numbers_are_jumpers no)
		(fp_line
			(start 0.7874 0.4064)
			(end 0.7874 -0.4064)
			(stroke
				(width 0.1524)
				(type default)
			)
			(layer "B.SilkS")
		)
		(fp_line
			(start 0.7874 -0.4064)
			(end -0.7874 -0.4064)
			(stroke
				(width 0.1524)
				(type default)
			)
			(layer "B.SilkS")
		)
		(fp_line
			(start -0.7874 0.4064)
			(end 0.7874 0.4064)
			(stroke
				(width 0.1524)
				(type default)
			)
			(layer "B.SilkS")
		)
		(fp_line
			(start -0.7874 -0.4064)
			(end -0.7874 0.4064)
			(stroke
				(width 0.1524)
				(type default)
			)
			(layer "B.SilkS")
		)
		(fp_line
			(start 0.67945 0.3048)
			(end 0.67945 -0.305054)
			(stroke
				(width 0.1)
				(type default)
			)
			(layer "B.Fab")
		)
		(fp_line
			(start 0.67945 -0.305054)
			(end 0.12065 -0.305054)
			(stroke
				(width 0.1)
				(type default)
			)
			(layer "B.Fab")
		)
		(fp_line
			(start 0.12065 0.3048)
			(end 0.67945 0.3048)
			(stroke
				(width 0.1)
				(type default)
			)
			(layer "B.Fab")
		)
		(fp_line
			(start 0.12065 0.2794)
			(end 0.12065 0.3048)
			(stroke
				(width 0.1)
				(type default)
			)
			(layer "B.Fab")
		)
		(fp_line
			(start 0.12065 -0.2794)
			(end -0.12065 -0.2794)
			(stroke
				(width 0.1)
				(type default)
			)
			(layer "B.Fab")
		)
		(fp_line
			(start 0.12065 -0.305054)
			(end 0.12065 -0.2794)
			(stroke
				(width 0.1)
				(type default)
			)
			(layer "B.Fab")
		)
		(fp_line
			(start -0.120396 0.3048)
			(end -0.120396 0.2794)
			(stroke
				(width 0.1)
				(type default)
			)
			(layer "B.Fab")
		)
		(fp_line
			(start -0.120396 0.2794)
			(end 0.12065 0.2794)
			(stroke
				(width 0.1)
				(type default)
			)
			(layer "B.Fab")
		)
		(fp_line
			(start -0.12065 -0.2794)
			(end -0.12065 -0.3048)
			(stroke
				(width 0.1)
				(type default)
			)
			(layer "B.Fab")
		)
		(fp_line
			(start -0.12065 -0.3048)
			(end -0.67945 -0.3048)
			(stroke
				(width 0.1)
				(type default)
			)
			(layer "B.Fab")
		)
		(fp_line
			(start -0.67945 0.3048)
			(end -0.120396 0.3048)
			(stroke
				(width 0.1)
				(type default)
			)
			(layer "B.Fab")
		)
		(fp_line
			(start -0.67945 -0.3048)
			(end -0.67945 0.3048)
			(stroke
				(width 0.1)
				(type default)
			)
			(layer "B.Fab")
		)
		(pad "1" smd circle
			(at 0.40005 0)
			(size 0 0)
			(layers "B.Cu" "B.Mask" "B.Paste")
			(net "P3V3_AUX_CLK_GEN_VDDA25M_CK440")
		)
		(pad "2" smd circle
			(at -0.40005 0)
			(size 0 0)
			(layers "B.Cu" "B.Mask" "B.Paste")
			(net "GND")
		)
	)
)
